(kicad_pcb
	(version 20260206)
	(generator "pcbnew")
	(generator_version "10.0")
	(general
		(thickness 1.6)
		(legacy_teardrops no)
	)
	(paper "A4")
	(title_block
		(title "Wiwynn_Tioga_Pass_MB.brd")
		(comment 1 "Tioga Pass / footprint 2254 of 4770 (U5D1), pads 1229-1322 of 3647")
	)
	(layers
		(0 "F.Cu" signal "TOP")
		(4 "In1.Cu" signal "L2GND")
		(6 "In2.Cu" signal "L3")
		(8 "In3.Cu" signal "L4GND")
		(10 "In4.Cu" signal "L5")
		(12 "In5.Cu" signal "L6GND")
		(14 "In6.Cu" signal "L7VCC")
		(16 "In7.Cu" signal "L8VCC")
		(18 "In8.Cu" signal "L9GND")
		(20 "In9.Cu" signal "L10")
		(22 "In10.Cu" signal "L11GND")
		(24 "In11.Cu" signal "L12")
		(26 "In12.Cu" signal "L13GND")
		(2 "B.Cu" signal "BOTTOM")
		(9 "F.Adhes" user "F.Adhesive")
		(11 "B.Adhes" user "B.Adhesive")
		(13 "F.Paste" user "Package Geometry/Pastemask Top")
		(15 "B.Paste" user "Package Geometry/Pastemask Bottom")
		(5 "F.SilkS" user "Ref Des/Silkscreen Top")
		(7 "B.SilkS" user "Ref Des/Silkscreen Bottom")
		(1 "F.Mask" user "Board Geometry/Soldermask Top")
		(3 "B.Mask" user "Board Geometry/Soldermask Bottom")
		(17 "Dwgs.User" user "User.Drawings")
		(19 "Cmts.User" user "User.Comments")
		(21 "Eco1.User" user "User.Eco1")
		(23 "Eco2.User" user "User.Eco2")
		(25 "Edge.Cuts" user "Board Geometry/Outline")
		(27 "Margin" user)
		(31 "F.CrtYd" user "Package Geometry/Place Bound Top")
		(29 "B.CrtYd" user "Package Geometry/Place Bound Bottom")
		(35 "F.Fab" user "Ref Des/Assembly Top")
		(33 "B.Fab" user "Ref Des/Assembly Bottom")
	)
	(footprint ""
		(layer "F.Cu")
		(at 270.000222 -76.550012 180)
		(property "Reference" "U5D1"
			(at 19.124422 31.601918 0)
			(unlocked yes)
			(layer "F.SilkS")
			(effects
				(font
					(size 0.7874 0.5842)
					(thickness 0.1524)
				)
			)
		)
		(property "Value" ""
			(at 0 0 180)
			(layer "F.Fab")
			(effects
				(font
					(size 1.27 1.27)
				)
			)
		)
		(duplicate_pad_numbers_are_jumpers no)
		(pad "BW66" smd circle
			(at 20.080478 1.824228)
			(size 0.4318 0.4318)
			(layers "F.Cu" "F.Mask" "F.Paste")
			(net "PVCCIN_CPU0")
		)
		(pad "BW68" smd circle
			(at 21.797518 1.824228)
			(size 0.4318 0.4318)
			(layers "F.Cu" "F.Mask" "F.Paste")
			(net "PVCCIN_CPU0")
		)
		(pad "BW70" smd circle
			(at 23.514558 1.824228)
			(size 0.4318 0.4318)
			(layers "F.Cu" "F.Mask" "F.Paste")
			(net "PVCCIN_CPU0")
		)
		(pad "BW72" smd circle
			(at 25.231598 1.824228)
			(size 0.4318 0.4318)
			(layers "F.Cu" "F.Mask" "F.Paste")
			(net "GND")
		)
		(pad "BW74" smd circle
			(at 26.948384 1.824228)
			(size 0.4318 0.4318)
			(layers "F.Cu" "F.Mask" "F.Paste")
			(net "GND")
		)
		(pad "BW76" smd circle
			(at 28.665424 1.824228)
			(size 0.4318 0.4318)
			(layers "F.Cu" "F.Mask" "F.Paste")
			(net "GND")
		)
		(pad "BW78" smd circle
			(at 30.382464 1.824228)
			(size 0.4318 0.4318)
			(layers "F.Cu" "F.Mask" "F.Paste")
			(net "GND")
		)
		(pad "BW80" smd circle
			(at 32.099504 1.824228)
			(size 0.4318 0.4318)
			(layers "F.Cu" "F.Mask" "F.Paste")
			(net "GND")
		)
		(pad "BW82" smd circle
			(at 33.816544 1.824228)
			(size 0.4318 0.4318)
			(layers "F.Cu" "F.Mask" "F.Paste")
			(net "GND")
		)
		(pad "BW84" smd custom
			(at 35.533584 1.824228 270)
			(size 0.10795 0.10795)
			(layers "F.Cu" "F.Mask" "F.Paste")
			(net "PVCCIN_CPU0")
			(options
				(clearance outline)
				(anchor circle)
			)
			(primitives
				(gr_poly
					(pts
						(arc
							(start 0.2159 -0.0381)
							(mid 0 -0.254)
							(end -0.2159 -0.0381)
						)
						(arc
							(start -0.2159 0.0381)
							(mid 0 0.254)
							(end 0.2159 0.0381)
						)
					)
					(width 0)
					(fill yes)
				)
			)
		)
		(pad "BY3" smd custom
			(at -35.533584 4.119372 90)
			(size 0.10795 0.10795)
			(layers "F.Cu" "F.Mask" "F.Paste")
			(net "P3E_CPU0_PE2_SS_TXP<9>")
			(options
				(clearance outline)
				(anchor circle)
			)
			(primitives
				(gr_poly
					(pts
						(arc
							(start 0.2159 -0.0381)
							(mid 0 -0.254)
							(end -0.2159 -0.0381)
						)
						(arc
							(start -0.2159 0.0381)
							(mid 0 0.254)
							(end 0.2159 0.0381)
						)
					)
					(width 0)
					(fill yes)
				)
			)
		)
		(pad "BY5" smd circle
			(at -33.816544 4.119372)
			(size 0.4318 0.4318)
			(layers "F.Cu" "F.Mask" "F.Paste")
			(net "P3E_CPU0_PE2_SS_TXP<10>")
		)
		(pad "BY7" smd circle
			(at -32.099504 4.119372)
			(size 0.4318 0.4318)
			(layers "F.Cu" "F.Mask" "F.Paste")
			(net "P3E_CPU0_PE2_SS_RXN<9>")
		)
		(pad "BY9" smd circle
			(at -30.382464 4.119372)
			(size 0.4318 0.4318)
			(layers "F.Cu" "F.Mask" "F.Paste")
			(net "P3E_CPU0_PE2_SS_RXN<8>")
		)
		(pad "BY11" smd circle
			(at -28.665424 4.119372)
			(size 0.4318 0.4318)
			(layers "F.Cu" "F.Mask" "F.Paste")
			(net "GND")
		)
		(pad "BY13" smd circle
			(at -26.948384 4.119372)
			(size 0.4318 0.4318)
			(layers "F.Cu" "F.Mask" "F.Paste")
			(net "GND")
		)
		(pad "BY15" smd circle
			(at -25.231598 4.119372)
			(size 0.4318 0.4318)
			(layers "F.Cu" "F.Mask" "F.Paste")
			(net "GND")
		)
		(pad "BY17" smd circle
			(at -23.514558 4.119372)
			(size 0.4318 0.4318)
			(layers "F.Cu" "F.Mask" "F.Paste")
			(net "GND")
		)
		(pad "BY19" smd circle
			(at -21.797518 4.119372)
			(size 0.4318 0.4318)
			(layers "F.Cu" "F.Mask" "F.Paste")
			(net "PVCCMCP_CPU0")
		)
		(pad "BY21" smd circle
			(at -20.080478 4.119372)
			(size 0.4318 0.4318)
			(layers "F.Cu" "F.Mask" "F.Paste")
			(net "JTAG_MCP_CPU0_TDI")
		)
		(pad "BY23" smd circle
			(at -18.363438 4.119372)
			(size 0.4318 0.4318)
			(layers "F.Cu" "F.Mask" "F.Paste")
			(net "GND")
		)
		(pad "BY25" smd circle
			(at -16.646398 4.119372)
			(size 0.4318 0.4318)
			(layers "F.Cu" "F.Mask" "F.Paste")
			(net "TP_CPU0_RSVD_119")
		)
		(pad "BY27" smd circle
			(at -14.929612 4.119372)
			(size 0.4318 0.4318)
			(layers "F.Cu" "F.Mask" "F.Paste")
			(net "P1V8_MCP_CPU0")
		)
		(pad "BY61" smd circle
			(at 15.787878 2.319274)
			(size 0.4318 0.4318)
			(layers "F.Cu" "F.Mask" "F.Paste")
			(net "PVCCIN_CPU0")
		)
		(pad "BY63" smd circle
			(at 17.504918 2.319274)
			(size 0.4318 0.4318)
			(layers "F.Cu" "F.Mask" "F.Paste")
			(net "GND")
		)
		(pad "BY65" smd circle
			(at 19.221958 2.319274)
			(size 0.4318 0.4318)
			(layers "F.Cu" "F.Mask" "F.Paste")
			(net "GND")
		)
		(pad "BY67" smd circle
			(at 20.938998 2.319274)
			(size 0.4318 0.4318)
			(layers "F.Cu" "F.Mask" "F.Paste")
			(net "GND")
		)
		(pad "BY69" smd circle
			(at 22.656038 2.319274)
			(size 0.4318 0.4318)
			(layers "F.Cu" "F.Mask" "F.Paste")
			(net "GND")
		)
		(pad "BY71" smd circle
			(at 24.373078 2.319274)
			(size 0.4318 0.4318)
			(layers "F.Cu" "F.Mask" "F.Paste")
			(net "GND")
		)
		(pad "BY73" smd circle
			(at 26.090118 2.319274)
			(size 0.4318 0.4318)
			(layers "F.Cu" "F.Mask" "F.Paste")
			(net "PVCCIN_CPU0")
		)
		(pad "BY75" smd circle
			(at 27.806904 2.319274)
			(size 0.4318 0.4318)
			(layers "F.Cu" "F.Mask" "F.Paste")
			(net "PVCCIN_CPU0")
		)
		(pad "BY77" smd circle
			(at 29.523944 2.319274)
			(size 0.4318 0.4318)
			(layers "F.Cu" "F.Mask" "F.Paste")
			(net "PVCCIN_CPU0")
		)
		(pad "BY79" smd circle
			(at 31.240984 2.319274)
			(size 0.4318 0.4318)
			(layers "F.Cu" "F.Mask" "F.Paste")
			(net "PVCCIN_CPU0")
		)
		(pad "BY81" smd circle
			(at 32.958024 2.319274)
			(size 0.4318 0.4318)
			(layers "F.Cu" "F.Mask" "F.Paste")
			(net "PVCCIN_CPU0")
		)
		(pad "BY83" smd circle
			(at 34.675064 2.319274)
			(size 0.4318 0.4318)
			(layers "F.Cu" "F.Mask" "F.Paste")
			(net "PVCCIN_CPU0")
		)
		(pad "C4" smd custom
			(at -34.675064 -24.112474 45)
			(size 0.10795 0.10795)
			(layers "F.Cu" "F.Mask" "F.Paste")
			(net "GND")
			(options
				(clearance outline)
				(anchor circle)
			)
			(primitives
				(gr_poly
					(pts
						(arc
							(start 0.2159 -0.0381)
							(mid 0 -0.254)
							(end -0.2159 -0.0381)
						)
						(arc
							(start -0.2159 0.0381)
							(mid 0 0.254)
							(end 0.2159 0.0381)
						)
					)
					(width 0)
					(fill yes)
				)
			)
		)
		(pad "C6" smd custom
			(at -32.958024 -24.112474)
			(size 0.10795 0.10795)
			(layers "F.Cu" "F.Mask" "F.Paste")
			(net "TP_CPU0_RSVD_291")
			(options
				(clearance outline)
				(anchor circle)
			)
			(primitives
				(gr_poly
					(pts
						(arc
							(start 0.2159 -0.0381)
							(mid 0 -0.254)
							(end -0.2159 -0.0381)
						)
						(arc
							(start -0.2159 0.0381)
							(mid 0 0.254)
							(end 0.2159 0.0381)
						)
					)
					(width 0)
					(fill yes)
				)
			)
		)
		(pad "C8" smd circle
			(at -31.240984 -24.112474)
			(size 0.4318 0.4318)
			(layers "F.Cu" "F.Mask" "F.Paste")
			(net "GND")
		)
		(pad "C10" smd circle
			(at -29.523944 -24.112474)
			(size 0.4318 0.4318)
			(layers "F.Cu" "F.Mask" "F.Paste")
			(net "GND")
		)
		(pad "C12" smd circle
			(at -27.806904 -24.112474)
			(size 0.4318 0.4318)
			(layers "F.Cu" "F.Mask" "F.Paste")
			(net "GND")
		)
		(pad "C14" smd circle
			(at -26.090118 -24.112474)
			(size 0.4318 0.4318)
			(layers "F.Cu" "F.Mask" "F.Paste")
			(net "GND")
		)
		(pad "C16" smd circle
			(at -24.373078 -24.112474)
			(size 0.4318 0.4318)
			(layers "F.Cu" "F.Mask" "F.Paste")
			(net "GND")
		)
		(pad "C18" smd custom
			(at -22.656038 -24.112474)
			(size 0.10795 0.10795)
			(layers "F.Cu" "F.Mask" "F.Paste")
			(net "TP_CPU0_RSVD_290")
			(options
				(clearance outline)
				(anchor circle)
			)
			(primitives
				(gr_poly
					(pts
						(arc
							(start 0.2159 -0.0381)
							(mid 0 -0.254)
							(end -0.2159 -0.0381)
						)
						(arc
							(start -0.2159 0.0381)
							(mid 0 0.254)
							(end 0.2159 0.0381)
						)
					)
					(width 0)
					(fill yes)
				)
			)
		)
		(pad "C24" smd custom
			(at -17.504918 -24.112474)
			(size 0.10795 0.10795)
			(layers "F.Cu" "F.Mask" "F.Paste")
			(net "TP_CPU0_RSVD_289")
			(options
				(clearance outline)
				(anchor circle)
			)
			(primitives
				(gr_poly
					(pts
						(arc
							(start 0.2159 -0.0381)
							(mid 0 -0.254)
							(end -0.2159 -0.0381)
						)
						(arc
							(start -0.2159 0.0381)
							(mid 0 0.254)
							(end 0.2159 0.0381)
						)
					)
					(width 0)
					(fill yes)
				)
			)
		)
		(pad "C26" smd circle
			(at -15.787878 -24.112474)
			(size 0.4318 0.4318)
			(layers "F.Cu" "F.Mask" "F.Paste")
			(net "M_B_DQ<50>")
		)
		(pad "C28" smd circle
			(at -14.071092 -24.112474)
			(size 0.4318 0.4318)
			(layers "F.Cu" "F.Mask" "F.Paste")
			(net "M_B_DQS_DP<15>")
		)
		(pad "C30" smd circle
			(at -12.354052 -24.112474)
			(size 0.4318 0.4318)
			(layers "F.Cu" "F.Mask" "F.Paste")
			(net "M_B_DQ<48>")
		)
		(pad "C32" smd circle
			(at -10.637012 -24.112474)
			(size 0.4318 0.4318)
			(layers "F.Cu" "F.Mask" "F.Paste")
			(net "M_B_DQ<42>")
		)
		(pad "C34" smd circle
			(at -8.919972 -24.112474)
			(size 0.4318 0.4318)
			(layers "F.Cu" "F.Mask" "F.Paste")
			(net "M_B_DQS_DP<14>")
		)
		(pad "C36" smd circle
			(at -7.202932 -24.112474)
			(size 0.4318 0.4318)
			(layers "F.Cu" "F.Mask" "F.Paste")
			(net "M_B_DQ<40>")
		)
		(pad "C38" smd circle
			(at -5.485892 -24.112474)
			(size 0.4318 0.4318)
			(layers "F.Cu" "F.Mask" "F.Paste")
			(net "M_A_DQ<34>")
		)
		(pad "C40" smd circle
			(at -3.769106 -24.112474)
			(size 0.4318 0.4318)
			(layers "F.Cu" "F.Mask" "F.Paste")
			(net "M_A_DQS_DP<13>")
		)
		(pad "C42" smd circle
			(at -2.052066 -24.112474)
			(size 0.4318 0.4318)
			(layers "F.Cu" "F.Mask" "F.Paste")
			(net "M_A_DQ<32>")
		)
		(pad "C46" smd custom
			(at 2.910586 -25.912572 45)
			(size 0.10795 0.10795)
			(layers "F.Cu" "F.Mask" "F.Paste")
			(net "PVDDQ_ABC")
			(options
				(clearance outline)
				(anchor circle)
			)
			(primitives
				(gr_poly
					(pts
						(arc
							(start 0.2159 -0.0381)
							(mid 0 -0.254)
							(end -0.2159 -0.0381)
						)
						(arc
							(start -0.2159 0.0381)
							(mid 0 0.254)
							(end 0.2159 0.0381)
						)
					)
					(width 0)
					(fill yes)
				)
			)
		)
		(pad "C48" smd circle
			(at 4.627626 -25.912572)
			(size 0.4318 0.4318)
			(layers "F.Cu" "F.Mask" "F.Paste")
			(net "M_A_ODT<1>")
		)
		(pad "C50" smd circle
			(at 6.344412 -25.912572)
			(size 0.4318 0.4318)
			(layers "F.Cu" "F.Mask" "F.Paste")
			(net "M_A_ODT<0>")
		)
		(pad "C52" smd circle
			(at 8.061452 -25.912572)
			(size 0.4318 0.4318)
			(layers "F.Cu" "F.Mask" "F.Paste")
			(net "M_A_BA<0>")
		)
		(pad "C54" smd circle
			(at 9.778492 -25.912572)
			(size 0.4318 0.4318)
			(layers "F.Cu" "F.Mask" "F.Paste")
			(net "M_A_CLK_DN<1>")
		)
		(pad "C56" smd circle
			(at 11.495532 -25.912572)
			(size 0.4318 0.4318)
			(layers "F.Cu" "F.Mask" "F.Paste")
			(net "M_A_CLK_DN<3>")
		)
		(pad "C58" smd circle
			(at 13.212572 -25.912572)
			(size 0.4318 0.4318)
			(layers "F.Cu" "F.Mask" "F.Paste")
			(net "M_A_MA<3>")
		)
		(pad "C60" smd circle
			(at 14.929612 -25.912572)
			(size 0.4318 0.4318)
			(layers "F.Cu" "F.Mask" "F.Paste")
			(net "M_A_MA<8>")
		)
		(pad "C62" smd circle
			(at 16.646398 -25.912572)
			(size 0.4318 0.4318)
			(layers "F.Cu" "F.Mask" "F.Paste")
			(net "M_A_CKE<0>")
		)
		(pad "C64" smd custom
			(at 18.363438 -25.912572)
			(size 0.10795 0.10795)
			(layers "F.Cu" "F.Mask" "F.Paste")
			(net "M_A_CKE<1>")
			(options
				(clearance outline)
				(anchor circle)
			)
			(primitives
				(gr_poly
					(pts
						(arc
							(start 0.2159 -0.0381)
							(mid 0 -0.254)
							(end -0.2159 -0.0381)
						)
						(arc
							(start -0.2159 0.0381)
							(mid 0 0.254)
							(end 0.2159 0.0381)
						)
					)
					(width 0)
					(fill yes)
				)
			)
		)
		(pad "C72" smd circle
			(at 25.231598 -25.912572)
			(size 0.4318 0.4318)
			(layers "F.Cu" "F.Mask" "F.Paste")
			(net "M_B_DQ<30>")
		)
		(pad "C74" smd circle
			(at 26.948384 -25.912572)
			(size 0.4318 0.4318)
			(layers "F.Cu" "F.Mask" "F.Paste")
			(net "M_B_DQ<25>")
		)
		(pad "C76" smd circle
			(at 28.665424 -25.912572)
			(size 0.4318 0.4318)
			(layers "F.Cu" "F.Mask" "F.Paste")
			(net "GND")
		)
		(pad "C78" smd circle
			(at 30.382464 -25.912572)
			(size 0.4318 0.4318)
			(layers "F.Cu" "F.Mask" "F.Paste")
			(net "GND")
		)
		(pad "C80" smd custom
			(at 32.099504 -25.912572 315)
			(size 0.10795 0.10795)
			(layers "F.Cu" "F.Mask" "F.Paste")
			(net "GND")
			(options
				(clearance outline)
				(anchor circle)
			)
			(primitives
				(gr_poly
					(pts
						(arc
							(start 0.2159 -0.0381)
							(mid 0 -0.254)
							(end -0.2159 -0.0381)
						)
						(arc
							(start -0.2159 0.0381)
							(mid 0 0.254)
							(end 0.2159 0.0381)
						)
					)
					(width 0)
					(fill yes)
				)
			)
		)
		(pad "C82" smd custom
			(at 33.816544 -25.912572 315)
			(size 0.10795 0.10795)
			(layers "F.Cu" "F.Mask" "F.Paste")
			(net "TP_CPU0_RSVD_288")
			(options
				(clearance outline)
				(anchor circle)
			)
			(primitives
				(gr_poly
					(pts
						(arc
							(start 0.2159 -0.0381)
							(mid 0 -0.254)
							(end -0.2159 -0.0381)
						)
						(arc
							(start -0.2159 0.0381)
							(mid 0 0.254)
							(end 0.2159 0.0381)
						)
					)
					(width 0)
					(fill yes)
				)
			)
		)
		(pad "CA2" smd custom
			(at -36.392104 4.614926 90)
			(size 0.10795 0.10795)
			(layers "F.Cu" "F.Mask" "F.Paste")
			(net "GND")
			(options
				(clearance outline)
				(anchor circle)
			)
			(primitives
				(gr_poly
					(pts
						(arc
							(start 0.2159 -0.0381)
							(mid 0 -0.254)
							(end -0.2159 -0.0381)
						)
						(arc
							(start -0.2159 0.0381)
							(mid 0 0.254)
							(end 0.2159 0.0381)
						)
					)
					(width 0)
					(fill yes)
				)
			)
		)
		(pad "CA4" smd circle
			(at -34.675064 4.614926)
			(size 0.4318 0.4318)
			(layers "F.Cu" "F.Mask" "F.Paste")
			(net "P3E_CPU0_PE2_SS_TXN<10>")
		)
		(pad "CA6" smd circle
			(at -32.958024 4.614926)
			(size 0.4318 0.4318)
			(layers "F.Cu" "F.Mask" "F.Paste")
			(net "GND")
		)
		(pad "CA8" smd circle
			(at -31.240984 4.614926)
			(size 0.4318 0.4318)
			(layers "F.Cu" "F.Mask" "F.Paste")
			(net "GND")
		)
		(pad "CA10" smd circle
			(at -29.523944 4.614926)
			(size 0.4318 0.4318)
			(layers "F.Cu" "F.Mask" "F.Paste")
			(net "GND")
		)
		(pad "CA12" smd circle
			(at -27.806904 4.614926)
			(size 0.4318 0.4318)
			(layers "F.Cu" "F.Mask" "F.Paste")
			(net "TP_CPU0_UPI2_RSVD_DP21")
		)
		(pad "CA14" smd circle
			(at -26.090118 4.614926)
			(size 0.4318 0.4318)
			(layers "F.Cu" "F.Mask" "F.Paste")
			(net "GND")
		)
		(pad "CA16" smd circle
			(at -24.373078 4.614926)
			(size 0.4318 0.4318)
			(layers "F.Cu" "F.Mask" "F.Paste")
			(net "GND")
		)
		(pad "CA18" smd circle
			(at -22.656038 4.614926)
			(size 0.4318 0.4318)
			(layers "F.Cu" "F.Mask" "F.Paste")
			(net "GND")
		)
		(pad "CA20" smd circle
			(at -20.938998 4.614926)
			(size 0.4318 0.4318)
			(layers "F.Cu" "F.Mask" "F.Paste")
			(net "GND")
		)
		(pad "CA22" smd circle
			(at -19.221958 4.614926)
			(size 0.4318 0.4318)
			(layers "F.Cu" "F.Mask" "F.Paste")
			(net "PVCCMCP_CPU0")
		)
		(pad "CA24" smd circle
			(at -17.504918 4.614926)
			(size 0.4318 0.4318)
			(layers "F.Cu" "F.Mask" "F.Paste")
			(net "TP_CPU0_RSVD_117")
		)
		(pad "CA26" smd circle
			(at -15.787878 4.614926)
			(size 0.4318 0.4318)
			(layers "F.Cu" "F.Mask" "F.Paste")
			(net "GND")
		)
		(pad "CA60" smd circle
			(at 14.929612 2.814828)
			(size 0.508 0.508)
			(layers "F.Cu" "F.Mask" "F.Paste")
			(net "PVCCIN_CPU0")
		)
		(pad "CA62" smd circle
			(at 16.646398 2.814828)
			(size 0.4318 0.4318)
			(layers "F.Cu" "F.Mask" "F.Paste")
			(net "PVCCIN_CPU0")
		)
		(pad "CA64" smd circle
			(at 18.363438 2.814828)
			(size 0.4318 0.4318)
			(layers "F.Cu" "F.Mask" "F.Paste")
			(net "GND")
		)
		(pad "CA66" smd circle
			(at 20.080478 2.814828)
			(size 0.4318 0.4318)
			(layers "F.Cu" "F.Mask" "F.Paste")
			(net "GND")
		)
		(pad "CA68" smd circle
			(at 21.797518 2.814828)
			(size 0.4318 0.4318)
			(layers "F.Cu" "F.Mask" "F.Paste")
			(net "GND")
		)
		(pad "CA70" smd circle
			(at 23.514558 2.814828)
			(size 0.4318 0.4318)
			(layers "F.Cu" "F.Mask" "F.Paste")
			(net "GND")
		)
		(pad "CA72" smd circle
			(at 25.231598 2.814828)
			(size 0.4318 0.4318)
			(layers "F.Cu" "F.Mask" "F.Paste")
			(net "PVCCIN_CPU0")
		)
		(pad "CA74" smd circle
			(at 26.948384 2.814828)
			(size 0.4318 0.4318)
			(layers "F.Cu" "F.Mask" "F.Paste")
			(net "PVCCIN_CPU0")
		)
		(pad "CA76" smd circle
			(at 28.665424 2.814828)
			(size 0.4318 0.4318)
			(layers "F.Cu" "F.Mask" "F.Paste")
			(net "PVCCIN_CPU0")
		)
		(pad "CA78" smd circle
			(at 30.382464 2.814828)
			(size 0.4318 0.4318)
			(layers "F.Cu" "F.Mask" "F.Paste")
			(net "PVCCIN_CPU0")
		)
		(pad "CA80" smd circle
			(at 32.099504 2.814828)
			(size 0.4318 0.4318)
			(layers "F.Cu" "F.Mask" "F.Paste")
			(net "PVCCIN_CPU0")
		)
		(pad "CA82" smd circle
			(at 33.816544 2.814828)
			(size 0.4318 0.4318)
			(layers "F.Cu" "F.Mask" "F.Paste")
			(net "PVCCIN_CPU0")
		)
	)
)
